(kicad_pcb
	(version 20241229)
	(generator "pcbnew")
	(generator_version "9.0")
	(general
		(thickness 1.62)
		(legacy_teardrops no)
	)
	(paper "A4")
	(title_block
		(title "OCuLink to 10GbE adapter")
		(date "2026-02-23")
		(rev "1.1.0")
		(company "Antmicro Ltd")
		(comment 1 "www.antmicro.com")
		(comment 9 "footprints 179-182 of 510")
	)
	(layers
		(0 "F.Cu" signal)
		(4 "In1.Cu" signal)
		(6 "In2.Cu" signal)
		(8 "In3.Cu" signal)
		(10 "In4.Cu" signal)
		(12 "In5.Cu" signal)
		(14 "In6.Cu" signal)
		(2 "B.Cu" signal)
		(9 "F.Adhes" user "F.Adhesive")
		(11 "B.Adhes" user "B.Adhesive")
		(13 "F.Paste" user)
		(15 "B.Paste" user)
		(5 "F.SilkS" user "F.Silkscreen")
		(7 "B.SilkS" user "B.Silkscreen")
		(1 "F.Mask" user)
		(3 "B.Mask" user)
		(17 "Dwgs.User" user "User.Drawings")
		(19 "Cmts.User" user "User.Comments")
		(21 "Eco1.User" user "User.Eco1")
		(23 "Eco2.User" user "User.Eco2")
		(25 "Edge.Cuts" user)
		(27 "Margin" user)
		(31 "F.CrtYd" user "F.Courtyard")
		(29 "B.CrtYd" user "B.Courtyard")
		(35 "F.Fab" user)
		(33 "B.Fab" user)
	)
	(footprint "antmicro-footprints:VQFN-HR-9_2x1.5mm"
		(layer "F.Cu")
		(at 56.1 111.15 -90)
		(property "Reference" "U4"
			(at 1.41 1.25 90)
			(layer "F.SilkS")
			(effects
				(font
					(size 0.7 0.7)
					(thickness 0.15)
				)
				(justify right top)
			)
		)
		(property "Value" "TPS566231P"
			(at -1.45 2.45 90)
			(layer "F.Fab")
			(hide yes)
			(effects
				(font
					(size 0.7 0.7)
					(thickness 0.15)
				)
				(justify right top)
			)
		)
		(property "Datasheet" "https://www.ti.com/lit/ds/symlink/tps566231.pdf"
			(at 0 -0.045 90)
			(layer "F.Fab")
			(hide yes)
			(effects
				(font
					(size 0.7 0.7)
					(thickness 0.15)
				)
				(justify right top)
			)
		)
		(property "Description" "Switching Voltage Regulators 3-V to 18-V, 6-A synchronous buck converter"
			(at -1.45 3.65 90)
			(layer "F.Fab")
			(hide yes)
			(effects
				(font
					(size 0.7 0.7)
					(thickness 0.15)
				)
				(justify right top)
			)
		)
		(property "Manufacturer" "Texas Instruments"
			(at 0 0 270)
			(unlocked yes)
			(layer "F.Fab")
			(hide yes)
			(effects
				(font
					(size 1 1)
					(thickness 0.15)
				)
			)
		)
		(property "MPN" "TPS566231PRQFR"
			(at 0 0 270)
			(unlocked yes)
			(layer "F.Fab")
			(hide yes)
			(effects
				(font
					(size 1 1)
					(thickness 0.15)
				)
			)
		)
		(property "Author" "Antmicro"
			(at 0 0 270)
			(unlocked yes)
			(layer "F.Fab")
			(hide yes)
			(effects
				(font
					(size 1 1)
					(thickness 0.15)
				)
			)
		)
		(property "License" "Apache-2.0"
			(at 0 0 270)
			(unlocked yes)
			(layer "F.Fab")
			(hide yes)
			(effects
				(font
					(size 1 1)
					(thickness 0.15)
				)
			)
		)
		(sheetname "/Power/")
		(sheetfile "power.kicad_sch")
		(attr smd)
		(fp_line
			(start -1 0.945)
			(end -0.695 0.945)
			(stroke
				(width 0.15)
				(type solid)
			)
			(layer "F.SilkS")
		)
		(fp_line
			(start 1 0.945)
			(end 0.2 0.945)
			(stroke
				(width 0.15)
				(type solid)
			)
			(layer "F.SilkS")
		)
		(fp_line
			(start -1 -0.945)
			(end -0.695 -0.945)
			(stroke
				(width 0.15)
				(type solid)
			)
			(layer "F.SilkS")
		)
		(fp_line
			(start 1 -0.945)
			(end 0.695 -0.945)
			(stroke
				(width 0.15)
				(type solid)
			)
			(layer "F.SilkS")
		)
		(fp_circle
			(center -1.18 -0.77)
			(end -1.13 -0.77)
			(stroke
				(width 0.15)
				(type solid)
			)
			(fill yes)
			(layer "F.SilkS")
		)
		(fp_rect
			(start -1.3 -1.05)
			(end 1.3 1.05)
			(stroke
				(width 0.05)
				(type solid)
			)
			(fill no)
			(layer "F.CrtYd")
		)
		(fp_rect
			(start -1 -0.75)
			(end 1 0.75)
			(stroke
				(width 0.15)
				(type solid)
			)
			(fill no)
			(layer "F.Fab")
		)
		(pad "1" smd roundrect
			(at -0.925 -0.5 270)
			(size 0.55 0.25)
			(layers "F.Cu" "F.Mask" "F.Paste")
			(roundrect_rratio 0.125)
			(net 328 "/Power/1V0_VCC")
			(pinfunction "V_{CC}")
			(pintype "passive")
		)
		(pad "2" smd roundrect
			(at -0.925 0 270)
			(size 0.55 0.25)
			(layers "F.Cu" "F.Mask" "F.Paste")
			(roundrect_rratio 0.125)
			(net 332 "/Power/1V0_FB")
			(pinfunction "FB")
			(pintype "input")
		)
		(pad "3" smd roundrect
			(at -0.925 0.5 270)
			(size 0.55 0.25)
			(layers "F.Cu" "F.Mask" "F.Paste")
			(roundrect_rratio 0.125)
			(net 377 "/Power/1V0_EN")
			(pinfunction "EN")
			(pintype "input")
		)
		(pad "4" smd roundrect
			(at -0.25 0.45 270)
			(size 0.25 1)
			(layers "F.Cu" "F.Mask" "F.Paste")
			(roundrect_rratio 0.125)
			(net 28 "GND")
			(pinfunction "PGND")
			(pintype "power_in")
		)
		(pad "5" smd roundrect
			(at 0.925 0.5 270)
			(size 0.55 0.25)
			(layers "F.Cu" "F.Mask" "F.Paste")
			(roundrect_rratio 0.125)
			(net 314 "VCC")
			(pinfunction "V_{IN}")
			(pintype "power_in")
		)
		(pad "6" smd roundrect
			(at 0.925 0 270)
			(size 0.55 0.25)
			(layers "F.Cu" "F.Mask" "F.Paste")
			(roundrect_rratio 0.125)
			(net 314 "VCC")
			(pinfunction "V_{IN}")
			(pintype "passive")
		)
		(pad "7" smd roundrect
			(at 0.925 -0.5 270)
			(size 0.55 0.25)
			(layers "F.Cu" "F.Mask" "F.Paste")
			(roundrect_rratio 0.125)
			(net 327 "/Power/1V0_BST")
			(pinfunction "BST")
			(pintype "passive")
		)
		(pad "8" smd roundrect
			(at 0.25 -0.3 270)
			(size 0.25 1.3)
			(layers "F.Cu" "F.Mask" "F.Paste")
			(roundrect_rratio 0.125)
			(net 337 "/Power/1V0_SW")
			(pinfunction "SW")
			(pintype "power_out")
		)
		(pad "9" smd roundrect
			(at -0.25 -0.675 270)
			(size 0.25 0.55)
			(layers "F.Cu" "F.Mask" "F.Paste")
			(roundrect_rratio 0.125)
			(net 341 "/Power/1V0_PG")
			(pinfunction "PG")
			(pintype "passive")
		)
	)
	(footprint "antmicro-footprints:SOD-123FL"
		(layer "F.Cu")
		(at 111.265 116.355 -90)
		(property "Reference" "D14"
			(at -0.2 2.05 90)
			(layer "F.SilkS")
			(effects
				(font
					(size 0.7 0.7)
					(thickness 0.15)
				)
				(justify right top)
			)
		)
		(property "Value" "SZSMF4L14AT3G"
			(at 0 1.967 90)
			(layer "F.Fab")
			(hide yes)
			(effects
				(font
					(size 0.7 0.7)
					(thickness 0.15)
				)
				(justify right top)
			)
		)
		(property "Datasheet" "https://www.mouser.com/datasheet/2/240/media-3320461.pdf"
			(at 0 0 90)
			(layer "F.Fab")
			(hide yes)
			(effects
				(font
					(size 1.27 1.27)
					(thickness 0.15)
				)
			)
		)
		(property "Description" "ESD, TVS Diode, 14V, UNI, 400W, SOD-123FL"
			(at 0 0 90)
			(layer "F.Fab")
			(hide yes)
			(effects
				(font
					(size 1.27 1.27)
					(thickness 0.15)
				)
			)
		)
		(property "MPN" "SZSMF4L12AT3G"
			(at 0 0 270)
			(unlocked yes)
			(layer "F.Fab")
			(hide yes)
			(effects
				(font
					(size 1 1)
					(thickness 0.15)
				)
			)
		)
		(property "Author" "Antmicro"
			(at 0 0 270)
			(unlocked yes)
			(layer "F.Fab")
			(hide yes)
			(effects
				(font
					(size 1 1)
					(thickness 0.15)
				)
			)
		)
		(property "License" "Apache-2.0"
			(at 0 0 270)
			(unlocked yes)
			(layer "F.Fab")
			(hide yes)
			(effects
				(font
					(size 1 1)
					(thickness 0.15)
				)
			)
		)
		(property "Manufacturer" "Littelfuse"
			(at 0 0 270)
			(unlocked yes)
			(layer "F.Fab")
			(hide yes)
			(effects
				(font
					(size 1 1)
					(thickness 0.15)
				)
			)
		)
		(sheetname "/Fan controller/")
		(sheetfile "fan-controller.kicad_sch")
		(attr smd exclude_from_pos_files exclude_from_bom dnp)
		(fp_line
			(start -2.3 1.1)
			(end 0 1.1)
			(stroke
				(width 0.15)
				(type solid)
			)
			(layer "F.SilkS")
		)
		(fp_line
			(start -2.3 -1.1)
			(end -2.3 1.1)
			(stroke
				(width 0.15)
				(type solid)
			)
			(layer "F.SilkS")
		)
		(fp_line
			(start 0 -1.1)
			(end -2.3 -1.1)
			(stroke
				(width 0.15)
				(type solid)
			)
			(layer "F.SilkS")
		)
		(fp_rect
			(start -2.35 -1.125)
			(end 2.35 1.125)
			(stroke
				(width 0.05)
				(type solid)
			)
			(fill no)
			(layer "F.CrtYd")
		)
		(fp_rect
			(start -1.825 -0.875)
			(end 1.824 0.873)
			(stroke
				(width 0.15)
				(type solid)
			)
			(fill no)
			(layer "F.Fab")
		)
		(fp_rect
			(start -0.775 -0.875)
			(end -0.525 0.875)
			(stroke
				(width 0.15)
				(type solid)
			)
			(fill yes)
			(layer "F.Fab")
		)
		(pad "1" smd roundrect
			(at -1.43 0 270)
			(size 1.34 1.8)
			(layers "F.Cu" "F.Mask" "F.Paste")
			(roundrect_rratio 0.14)
			(net 389 "/Fan controller/V_{FAN}")
			(pinfunction "C")
			(pintype "passive")
		)
		(pad "2" smd roundrect
			(at 1.429 0 270)
			(size 1.34 1.8)
			(layers "F.Cu" "F.Mask" "F.Paste")
			(roundrect_rratio 0.14)
			(net 28 "GND")
			(pinfunction "A")
			(pintype "passive")
		)
	)
	(footprint "antmicro-footprints:TSSOP-8_3x3mm_P0.65mm"
		(layer "F.Cu")
		(at 106.975 94.4 -90)
		(property "Reference" "U8"
			(at -3.1 -0.825 90)
			(layer "F.SilkS")
			(effects
				(font
					(size 0.7 0.7)
					(thickness 0.15)
				)
				(justify left bottom)
			)
		)
		(property "Value" "NTS0102_TSSOP"
			(at 0 2.8 90)
			(layer "F.Fab")
			(hide yes)
			(effects
				(font
					(size 0.7 0.7)
					(thickness 0.15)
				)
				(justify right top)
			)
		)
		(property "Datasheet" "https://www.mouser.com/datasheet/2/302/NTS0102-1127324.pdf"
			(at 0 0 90)
			(layer "F.Fab")
			(hide yes)
			(effects
				(font
					(size 1.27 1.27)
					(thickness 0.15)
				)
			)
		)
		(property "Description" "Transceiver, 1.65 V to 3.6 V, TSSOP-8"
			(at 0 0 90)
			(layer "F.Fab")
			(hide yes)
			(effects
				(font
					(size 1.27 1.27)
					(thickness 0.15)
				)
			)
		)
		(property "MPN" "NTS0102DP"
			(at 0 0 270)
			(unlocked yes)
			(layer "F.Fab")
			(hide yes)
			(effects
				(font
					(size 1 1)
					(thickness 0.15)
				)
			)
		)
		(property "Manufacturer" "NXP"
			(at 0 0 270)
			(unlocked yes)
			(layer "F.Fab")
			(hide yes)
			(effects
				(font
					(size 1 1)
					(thickness 0.15)
				)
			)
		)
		(property "Author" "Antmicro"
			(at 0 0 270)
			(unlocked yes)
			(layer "F.Fab")
			(hide yes)
			(effects
				(font
					(size 1 1)
					(thickness 0.15)
				)
			)
		)
		(property "License" "Apache-2.0"
			(at 0 0 270)
			(unlocked yes)
			(layer "F.Fab")
			(hide yes)
			(effects
				(font
					(size 1 1)
					(thickness 0.15)
				)
			)
		)
		(sheetname "/X710-AT2 Misc/")
		(sheetfile "x710-at2-mics.kicad_sch")
		(attr smd)
		(fp_line
			(start -1.55 1.561)
			(end 1.552 1.561)
			(stroke
				(width 0.15)
				(type solid)
			)
			(layer "F.SilkS")
		)
		(fp_line
			(start -1.525 -1.537)
			(end 1.552 -1.539)
			(stroke
				(width 0.15)
				(type solid)
			)
			(layer "F.SilkS")
		)
		(fp_circle
			(center -1.87 -1.4)
			(end -1.82 -1.4)
			(stroke
				(width 0.15)
				(type solid)
			)
			(fill yes)
			(layer "F.SilkS")
		)
		(fp_rect
			(start -3.15 -1.789)
			(end 3.15 1.811)
			(stroke
				(width 0.05)
				(type solid)
			)
			(fill no)
			(layer "F.CrtYd")
		)
		(fp_line
			(start -1.55 1.561)
			(end 1.552 1.561)
			(stroke
				(width 0.15)
				(type solid)
			)
			(layer "F.Fab")
		)
		(fp_line
			(start -1.55 -0.937)
			(end -1.55 1.561)
			(stroke
				(width 0.15)
				(type solid)
			)
			(layer "F.Fab")
		)
		(fp_line
			(start -1.55 -0.937)
			(end -0.949 -1.539)
			(stroke
				(width 0.15)
				(type solid)
			)
			(layer "F.Fab")
		)
		(fp_line
			(start -0.949 -1.539)
			(end 1.552 -1.539)
			(stroke
				(width 0.15)
				(type solid)
			)
			(layer "F.Fab")
		)
		(fp_line
			(start 1.552 -1.539)
			(end 1.552 1.561)
			(stroke
				(width 0.15)
				(type solid)
			)
			(layer "F.Fab")
		)
		(pad "1" smd roundrect
			(at -2.148 -0.962 270)
			(size 1.47 0.4)
			(layers "F.Cu" "F.Mask" "F.Paste")
			(roundrect_rratio 0.25)
			(net 215 "/X710-AT2 10GbE/MDIO0_I2C0.MDIO")
			(pinfunction "B_{2}")
			(pintype "bidirectional")
		)
		(pad "2" smd roundrect
			(at -2.148 -0.313 270)
			(size 1.47 0.4)
			(layers "F.Cu" "F.Mask" "F.Paste")
			(roundrect_rratio 0.25)
			(net 28 "GND")
			(pinfunction "GND")
			(pintype "power_in")
		)
		(pad "3" smd roundrect
			(at -2.148 0.338 270)
			(size 1.47 0.4)
			(layers "F.Cu" "F.Mask" "F.Paste")
			(roundrect_rratio 0.25)
			(net 18 "+1V88")
			(pinfunction "VCC_{A}")
			(pintype "power_in")
		)
		(pad "4" smd roundrect
			(at -2.148 0.987 270)
			(size 1.47 0.4)
			(layers "F.Cu" "F.Mask" "F.Paste")
			(roundrect_rratio 0.25)
			(net 381 "/X710-AT2 Misc/MDIO.MDIO")
			(pinfunction "A_{2}")
			(pintype "bidirectional")
		)
		(pad "5" smd roundrect
			(at 2.151 0.987 270)
			(size 1.47 0.4)
			(layers "F.Cu" "F.Mask" "F.Paste")
			(roundrect_rratio 0.25)
			(net 382 "/X710-AT2 Misc/MDIO.MDC")
			(pinfunction "A_{1}")
			(pintype "bidirectional")
		)
		(pad "6" smd roundrect
			(at 2.151 0.338 270)
			(size 1.47 0.4)
			(layers "F.Cu" "F.Mask" "F.Paste")
			(roundrect_rratio 0.25)
			(net 18 "+1V88")
			(pinfunction "OE")
			(pintype "input")
		)
		(pad "7" smd roundrect
			(at 2.151 -0.313 270)
			(size 1.47 0.4)
			(layers "F.Cu" "F.Mask" "F.Paste")
			(roundrect_rratio 0.25)
			(net 7 "+3V3")
			(pinfunction "VCC_{B}")
			(pintype "power_in")
		)
		(pad "8" smd roundrect
			(at 2.151 -0.962 270)
			(size 1.47 0.4)
			(layers "F.Cu" "F.Mask" "F.Paste")
			(roundrect_rratio 0.25)
			(net 288 "/X710-AT2 10GbE/MDIO0_I2C0.MDC")
			(pinfunction "B_{1}")
			(pintype "bidirectional")
		)
	)
	(footprint "antmicro-footprints:Conn_Molex_Nano-Fit_1x2_SMD_1054301202"
		(layer "F.Cu")
		(at 68.1 54.564 180)
		(descr "Molex Nano-Fit Power Connectors, 105430-xx02, 2 Pins per row")
		(tags "connector Molex Nano-Fit")
		(property "Reference" "J1"
			(at -4.59 -4.71 0)
			(layer "F.SilkS")
			(effects
				(font
					(size 0.7 0.7)
					(thickness 0.15)
				)
				(justify right top)
			)
		)
		(property "Value" "Molex_Nano-Fit_1x2_SMD_1054301202"
			(at 0 7.1 0)
			(layer "F.Fab")
			(hide yes)
			(effects
				(font
					(size 0.7 0.7)
					(thickness 0.15)
				)
				(justify right top)
			)
		)
		(property "Datasheet" "https://www.farnell.com/cad/3578051.pdf"
			(at 0 0 0)
			(layer "F.Fab")
			(hide yes)
			(effects
				(font
					(size 1.27 1.27)
					(thickness 0.15)
				)
			)
		)
		(property "Description" "Pin Header, Pitch 2.5 mm, 1 Row, 2 Contacts, Nano-Fit"
			(at 0 0 0)
			(layer "F.Fab")
			(hide yes)
			(effects
				(font
					(size 1.27 1.27)
					(thickness 0.15)
				)
			)
		)
		(property "Manufacturer" "Molex"
			(at 0 0 180)
			(unlocked yes)
			(layer "F.Fab")
			(hide yes)
			(effects
				(font
					(size 1 1)
					(thickness 0.15)
				)
			)
		)
		(property "MPN" "105430-1202"
			(at 0 0 180)
			(unlocked yes)
			(layer "F.Fab")
			(hide yes)
			(effects
				(font
					(size 1 1)
					(thickness 0.15)
				)
			)
		)
		(property "Author" "Antmicro"
			(at 0 0 180)
			(unlocked yes)
			(layer "F.Fab")
			(hide yes)
			(effects
				(font
					(size 1 1)
					(thickness 0.15)
				)
			)
		)
		(property "License" "Apache-2.0"
			(at 0 0 180)
			(unlocked yes)
			(layer "F.Fab")
			(hide yes)
			(effects
				(font
					(size 1 1)
					(thickness 0.15)
				)
			)
		)
		(sheetname "/Power/")
		(sheetfile "power.kicad_sch")
		(attr smd)
		(fp_line
			(start 4.48 2.298)
			(end 4.48 -4.5)
			(stroke
				(width 0.15)
				(type solid)
			)
			(layer "F.SilkS")
		)
		(fp_line
			(start 4.48 2.298)
			(end 4.28 2.698)
			(stroke
				(width 0.15)
				(type solid)
			)
			(layer "F.SilkS")
		)
		(fp_line
			(start 4.48 -4.5)
			(end 2.68 -4.5)
			(stroke
				(width 0.15)
				(type solid)
			)
			(layer "F.SilkS")
		)
		(fp_line
			(start 4.28 2.698)
			(end 4.28 4.299)
			(stroke
				(width 0.15)
				(type solid)
			)
			(layer "F.SilkS")
		)
		(fp_line
			(start -0.22 -4.5)
			(end 0.78 -4.5)
			(stroke
				(width 0.15)
				(type solid)
			)
			(layer "F.SilkS")
		)
		(fp_line
			(start -1.72 -4.5)
			(end -4.47 -4.5)
			(stroke
				(width 0.15)
				(type solid)
			)
			(layer "F.SilkS")
		)
		(fp_line
			(start -4.321 4.299)
			(end 4.28 4.299)
			(stroke
				(width 0.15)
				(type solid)
			)
			(layer "F.SilkS")
		)
		(fp_line
			(start -4.321 2.499)
			(end -4.321 4.299)
			(stroke
				(width 0.15)
				(type solid)
			)
			(layer "F.SilkS")
		)
		(fp_line
			(start -4.47 2.099)
			(end -4.321 2.499)
			(stroke
				(width 0.15)
				(type solid)
			)
			(layer "F.SilkS")
		)
		(fp_line
			(start -4.47 -4.5)
			(end -4.47 2.099)
			(stroke
				(width 0.15)
				(type solid)
			)
			(layer "F.SilkS")
		)
		(fp_circle
			(center 2.428 -4.91)
			(end 2.478 -4.91)
			(stroke
				(width 0.15)
				(type solid)
			)
			(fill yes)
			(layer "F.SilkS")
		)
		(fp_rect
			(start -4.77 -6.21)
			(end 4.77 6.11)
			(stroke
				(width 0.05)
				(type solid)
			)
			(fill no)
			(layer "F.CrtYd")
		)
		(pad "1" smd roundrect
			(at 1.528 -4.901 270)
			(size 2.5 1.24)
			(layers "F.Cu" "F.Mask" "F.Paste")
			(roundrect_rratio 0.25)
			(net 350 "/Power/+12V_IN")
			(pintype "passive")
		)
		(pad "2" smd roundrect
			(at -0.97 -4.901 270)
			(size 2.5 1.24)
			(layers "F.Cu" "F.Mask" "F.Paste")
			(roundrect_rratio 0.25)
			(net 28 "GND")
			(pintype "passive")
		)
		(pad "MP" smd roundrect
			(at -3.54 0.029 180)
			(size 1.1 8.2)
			(layers "F.Cu" "F.Mask" "F.Paste")
			(roundrect_rratio 0.25)
			(net 28 "GND")
			(pintype "passive")
		)
		(pad "MP" smd roundrect
			(at 3.499 0.029 180)
			(size 1.1 8.2)
			(layers "F.Cu" "F.Mask" "F.Paste")
			(roundrect_rratio 0.25)
			(net 28 "GND")
			(pintype "passive")
		)
	)
)
